FILE_TYPE = MACRO_DRAWING;
SET COLOR_WIRE YELLOW;
SET COLOR_PROP ORANGE;
SET COLOR_DOT WHITE;
SET COLOR_ARC YELLOW;
SET COLOR_BODY GREEN;
SET COLOR_NOTE PURPLE;
SET PROP_DISPLAY VALUE;
SET PAGE_NUMBER P442;
FORCEADD OFFPAGE..3
R 2
(-6875 5025);
FORCEPROP 2 LAST $XR1 186 
J 0
(-7275 5025);
DISPLAY 0.638298 (-7275 5025);
PAINT MONO (-7275 5025);
FORCEPROP 2 LAST $XR0 185 
J 0
(-7155 5025);
DISPLAY 0.638298 (-7155 5025);
PAINT MONO (-7155 5025);
FORCEPROP 2 LAST CDS_LIB standard
J 0
(-6875 5025);
DISPLAY INVISIBLE (-6875 5025);
FORCEPROP 1 LAST OFFPAGE TRUE
J 2
(-7200 4900);
DISPLAY 0.872340 (-7200 4900);
PAINT GREEN (-7200 4900);
DISPLAY INVISIBLE (-7200 4900);
FORCEPROP 1 LAST COMMENT_BODY TRUE
J 2
(-6825 4925);
DISPLAY 0.872340 (-6825 4925);
PAINT GREEN (-6825 4925);
DISPLAY INVISIBLE (-6825 4925);
FORCEPROP 2 LAST PATH I1
J 0
(-6825 5100);
DISPLAY 0.680851 (-6825 5100);
DISPLAY INVISIBLE (-6825 5100);
FORCEADD UNIVERSAL_GND..1
(-3025 4850);
FORCEPROP 3 LASTPIN (-3025 4900) SIG_NAME GND\g
J 0
(-3015 4910);
DISPLAY 0.659574 (-3015 4910);
PAINT MONO (-3015 4910);
DISPLAY INVISIBLE (-3015 4910);
FORCEPROP 2 LAST CDS_LIB pure_quanta_power
J 0
(-3025 4850);
DISPLAY INVISIBLE (-3025 4850);
FORCEPROP 1 LAST HDL_POWER GND
J 1
(-3000 4775);
DISPLAY 0.872340 (-3000 4775);
PAINT GREEN (-3000 4775);
DISPLAY INVISIBLE (-3000 4775);
FORCEPROP 1 LAST PATH I18
J 0
(-2950 4850);
DISPLAY 0.872340 (-2950 4850);
PAINT AQUA (-2950 4850);
DISPLAY INVISIBLE (-2950 4850);
FORCEADD Q_RES..2
(-2875 4900);
FORCEPROP 1 LAST LOCATION R6789
J 0
(-2830 5025);
DISPLAY 0.978723 (-2830 5025);
FORCEPROP 0 LAST $SEC 1
J 0
(-2825 5075);
DISPLAY 0.680851 (-2825 5075);
PAINT MONO (-2825 5075);
DISPLAY INVISIBLE (-2825 5075);
FORCEPROP 0 LAST CDS_SEC 1
J 0
(-2825 5075);
DISPLAY 0.680851 (-2825 5075);
DISPLAY INVISIBLE (-2825 5075);
FORCEPROP 1 LASTPIN (-2875 5000) $PN 1
J 0
(-2870 4962);
DISPLAY 0.787234 (-2870 4962);
PAINT MONO (-2870 4962);
FORCEPROP 1 LASTPIN (-2875 4800) $PN 2
J 0
(-2870 4810);
DISPLAY 0.787234 (-2870 4810);
PAINT MONO (-2870 4810);
FORCEPROP 1 LAST WATTAGE 1/20W
J 0
(-2835 4875);
DISPLAY 0.978723 (-2835 4875);
FORCEPROP 1 LAST TOLERANCE 1%
J 0
(-2830 4925);
DISPLAY 0.978723 (-2830 4925);
FORCEPROP 1 LAST VALUE 1K
J 0
(-2830 4975);
DISPLAY 0.978723 (-2830 4975);
FORCEPROP 1 LAST PACK_TYPE 0201LF
J 0
(-2835 4725);
DISPLAY 0.978723 (-2835 4725);
FORCEPROP 1 LAST MATERIAL CHIP
J 0
(-2835 4825);
DISPLAY 0.978723 (-2835 4825);
FORCEPROP 2 LAST CDS_LIB pure_quanta
J 0
(-2875 4900);
DISPLAY INVISIBLE (-2875 4900);
FORCEPROP 1 LAST PATH I19
J 0
(-2825 5075);
DISPLAY 0.978723 (-2825 5075);
PAINT WHITE (-2825 5075);
DISPLAY INVISIBLE (-2825 5075);
FORCEPROP 1 LAST PART_NUMBER CS21001FE07
J 0
(-2835 4775);
DISPLAY 0.978723 (-2835 4775);
DISPLAY INVISIBLE (-2835 4775);
FORCEADD OFFPAGE..1
(-6875 5075);
FORCEPROP 2 LAST $XR1 186 
J 0
(-7247 5075);
DISPLAY 0.638298 (-7247 5075);
PAINT MONO (-7247 5075);
FORCEPROP 2 LAST $XR0 185 
J 0
(-7127 5075);
DISPLAY 0.638298 (-7127 5075);
PAINT MONO (-7127 5075);
FORCEPROP 2 LAST CDS_LIB standard
J 0
(-6875 5075);
DISPLAY INVISIBLE (-6875 5075);
FORCEPROP 1 LAST OFFPAGE TRUE
J 0
(-6550 4950);
DISPLAY 0.872340 (-6550 4950);
DISPLAY INVISIBLE (-6550 4950);
FORCEPROP 1 LAST COMMENT_BODY TRUE
J 0
(-6750 4975);
DISPLAY 0.872340 (-6750 4975);
PAINT GREEN (-6750 4975);
DISPLAY INVISIBLE (-6750 4975);
FORCEPROP 2 LAST PATH I2
J 0
(-6825 5150);
DISPLAY 0.680851 (-6825 5150);
DISPLAY INVISIBLE (-6825 5150);
FORCEADD UNIVERSAL_GND..1
(-2875 4625);
FORCEPROP 3 LASTPIN (-2875 4675) SIG_NAME GND\g
J 0
(-2865 4685);
DISPLAY 0.659574 (-2865 4685);
PAINT MONO (-2865 4685);
DISPLAY INVISIBLE (-2865 4685);
FORCEPROP 2 LAST CDS_LIB pure_quanta_power
J 0
(-2875 4625);
DISPLAY INVISIBLE (-2875 4625);
FORCEPROP 1 LAST HDL_POWER GND
J 1
(-2850 4550);
DISPLAY 0.872340 (-2850 4550);
PAINT GREEN (-2850 4550);
DISPLAY INVISIBLE (-2850 4550);
FORCEPROP 1 LAST PATH I20
J 0
(-2800 4625);
DISPLAY 0.872340 (-2800 4625);
PAINT AQUA (-2800 4625);
DISPLAY INVISIBLE (-2800 4625);
FORCEADD P1V0..1
(-4325 5875);
FORCEPROP 3 LASTPIN (-4325 5825) SIG_NAME P1V8_CPU1_RT_1D\g
J 0
(-4315 5835);
DISPLAY 0.659574 (-4315 5835);
PAINT MONO (-4315 5835);
DISPLAY INVISIBLE (-4315 5835);
FORCEPROP 1 LAST HDL_POWER P1V8_CPU1_RT_1D
J 1
(-4325 5925);
DISPLAY 0.489362 (-4325 5925);
PAINT SKYBLUE (-4325 5925);
FORCEPROP 2 LAST CDS_LIB pure_quanta_power
J 0
(-4325 5875);
DISPLAY INVISIBLE (-4325 5875);
FORCEPROP 1 LAST PATH I21
J 0
(-4275 5900);
DISPLAY 0.872340 (-4275 5900);
PAINT AQUA (-4275 5900);
DISPLAY INVISIBLE (-4275 5900);
FORCEADD Q_CAP..1
(-4600 5625);
FORCEPROP 1 LAST LOCATION C7502
J 0
(-4550 5725);
DISPLAY 0.787234 (-4550 5725);
PAINT SKYBLUE (-4550 5725);
FORCEPROP 0 LAST $SEC 1
J 0
(-4550 5775);
DISPLAY 0.680851 (-4550 5775);
PAINT MONO (-4550 5775);
DISPLAY INVISIBLE (-4550 5775);
FORCEPROP 0 LAST CDS_SEC 1
J 0
(-4550 5775);
DISPLAY 0.680851 (-4550 5775);
DISPLAY INVISIBLE (-4550 5775);
FORCEPROP 1 LASTPIN (-4600 5725) $PN 1
J 0
(-4590 5705);
DISPLAY 0.787234 (-4590 5705);
PAINT MONO (-4590 5705);
FORCEPROP 1 LASTPIN (-4600 5525) $PN 2
J 0
(-4590 5505);
DISPLAY 0.787234 (-4590 5505);
PAINT MONO (-4590 5505);
FORCEPROP 1 LAST VOLTAGE 10V
J 0
(-4550 5625);
DISPLAY 0.510638 (-4550 5625);
FORCEPROP 1 LAST PACK_TYPE C0201
J 0
(-4550 5475);
DISPLAY 0.510638 (-4550 5475);
FORCEPROP 1 LAST TOLERANCE 10%
J 0
(-4550 5575);
DISPLAY 0.510638 (-4550 5575);
FORCEPROP 1 LAST MATERIAL X7S
J 0
(-4550 5525);
DISPLAY 0.510638 (-4550 5525);
FORCEPROP 1 LAST VALUE 0.1UF
J 0
(-4550 5675);
DISPLAY 0.510638 (-4550 5675);
FORCEPROP 2 LAST CDS_LIB pure_quanta
J 0
(-4600 5625);
DISPLAY INVISIBLE (-4600 5625);
FORCEPROP 1 LAST PATH I22
J 0
(-4550 5775);
DISPLAY 0.978723 (-4550 5775);
PAINT WHITE (-4550 5775);
DISPLAY INVISIBLE (-4550 5775);
FORCEPROP 1 LAST PART_NUMBER CH4102K6E00
J 0
(-4550 5475);
DISPLAY 0.978723 (-4550 5475);
DISPLAY INVISIBLE (-4550 5475);
FORCEADD UNIVERSAL_GND..1
(-4600 5325);
FORCEPROP 3 LASTPIN (-4600 5375) SIG_NAME GND\g
J 0
(-4590 5385);
DISPLAY 0.659574 (-4590 5385);
PAINT MONO (-4590 5385);
DISPLAY INVISIBLE (-4590 5385);
FORCEPROP 2 LAST CDS_LIB pure_quanta_power
J 0
(-4600 5325);
DISPLAY INVISIBLE (-4600 5325);
FORCEPROP 1 LAST HDL_POWER GND
J 1
(-4575 5250);
DISPLAY 0.872340 (-4575 5250);
PAINT GREEN (-4575 5250);
DISPLAY INVISIBLE (-4575 5250);
FORCEPROP 1 LAST PATH I23
J 0
(-4525 5325);
DISPLAY 0.872340 (-4525 5325);
PAINT AQUA (-4525 5325);
DISPLAY INVISIBLE (-4525 5325);
FORCEADD UNIVERSAL_GND..1
R 7
(-4325 5125);
FORCEPROP 3 LASTPIN (-4275 5125) SIG_NAME GND\g
J 0
(-4265 5135);
DISPLAY 0.659574 (-4265 5135);
PAINT MONO (-4265 5135);
DISPLAY INVISIBLE (-4265 5135);
FORCEPROP 2 LAST CDS_LIB pure_quanta_power
J 0
(-4325 5125);
DISPLAY INVISIBLE (-4325 5125);
FORCEPROP 1 LAST HDL_POWER GND
R 1
J 1
(-4400 5150);
DISPLAY 0.872340 (-4400 5150);
PAINT GREEN (-4400 5150);
DISPLAY INVISIBLE (-4400 5150);
FORCEPROP 1 LAST PATH I24
R 1
J 0
(-4325 5200);
DISPLAY 0.872340 (-4325 5200);
PAINT AQUA (-4325 5200);
DISPLAY INVISIBLE (-4325 5200);
FORCEADD Q_RES..1
(-5275 5025);
FORCEPROP 1 LAST LOCATION R690
J 0
(-5525 5025);
DISPLAY 0.978723 (-5525 5025);
FORCEPROP 0 LAST $SEC 1
J 0
(-5525 5075);
DISPLAY 0.680851 (-5525 5075);
PAINT MONO (-5525 5075);
DISPLAY INVISIBLE (-5525 5075);
FORCEPROP 0 LAST CDS_SEC 1
J 0
(-5525 5075);
DISPLAY 0.680851 (-5525 5075);
DISPLAY INVISIBLE (-5525 5075);
FORCEPROP 1 LASTPIN (-5375 5025) $PN 1
J 0
(-5363 5037);
DISPLAY 0.787234 (-5363 5037);
PAINT MONO (-5363 5037);
FORCEPROP 1 LASTPIN (-5175 5025) $PN 2
J 0
(-5213 5037);
DISPLAY 0.787234 (-5213 5037);
PAINT MONO (-5213 5037);
FORCEPROP 1 LAST PACK_TYPE 0201LF
J 0
(-5250 5100);
DISPLAY 0.787234 (-5250 5100);
DISPLAY INVISIBLE (-5250 5100);
FORCEPROP 1 LAST WATTAGE 1/20W
J 2
(-5475 5100);
DISPLAY 0.787234 (-5475 5100);
DISPLAY INVISIBLE (-5475 5100);
FORCEPROP 1 LAST MATERIAL CHIP
J 0
(-5450 5100);
DISPLAY 0.787234 (-5450 5100);
DISPLAY INVISIBLE (-5450 5100);
FORCEPROP 2 LAST CDS_LIB pure_quanta
J 0
(-5275 5025);
DISPLAY INVISIBLE (-5275 5025);
FORCEPROP 1 LAST VALUE 33.2
J 2
(-5475 5150);
DISPLAY 0.787234 (-5475 5150);
DISPLAY INVISIBLE (-5475 5150);
FORCEPROP 1 LAST TOLERANCE 1%
J 0
(-5450 5150);
DISPLAY 0.787234 (-5450 5150);
DISPLAY INVISIBLE (-5450 5150);
FORCEPROP 1 LAST PATH I3
J 0
(-5325 5175);
DISPLAY 0.978723 (-5325 5175);
PAINT WHITE (-5325 5175);
DISPLAY INVISIBLE (-5325 5175);
FORCEPROP 1 LAST PART_NUMBER CS03321FE09
J 0
(-5325 5150);
DISPLAY 0.808511 (-5325 5150);
DISPLAY INVISIBLE (-5325 5150);
FORCEADD Q_RES..1
(-5275 5075);
FORCEPROP 1 LAST LOCATION R689
J 0
(-5525 5075);
DISPLAY 0.978723 (-5525 5075);
FORCEPROP 0 LAST $SEC 1
J 0
(-5325 5250);
DISPLAY 0.680851 (-5325 5250);
PAINT MONO (-5325 5250);
DISPLAY INVISIBLE (-5325 5250);
FORCEPROP 0 LAST CDS_SEC 1
J 0
(-5325 5250);
DISPLAY 0.680851 (-5325 5250);
DISPLAY INVISIBLE (-5325 5250);
FORCEPROP 1 LASTPIN (-5375 5075) $PN 1
J 0
(-5363 5087);
DISPLAY 0.787234 (-5363 5087);
PAINT MONO (-5363 5087);
FORCEPROP 1 LASTPIN (-5175 5075) $PN 2
J 0
(-5213 5087);
DISPLAY 0.787234 (-5213 5087);
PAINT MONO (-5213 5087);
FORCEPROP 1 LAST WATTAGE 1/20W
J 2
(-5475 5150);
DISPLAY 0.787234 (-5475 5150);
FORCEPROP 1 LAST MATERIAL CHIP
J 0
(-5450 5150);
DISPLAY 0.787234 (-5450 5150);
FORCEPROP 1 LAST PACK_TYPE 0201LF
J 0
(-5250 5150);
DISPLAY 0.787234 (-5250 5150);
FORCEPROP 1 LAST VALUE 33.2
J 2
(-5475 5200);
DISPLAY 0.787234 (-5475 5200);
FORCEPROP 1 LAST TOLERANCE 1%
J 0
(-5450 5200);
DISPLAY 0.787234 (-5450 5200);
FORCEPROP 2 LAST CDS_LIB pure_quanta
J 0
(-5275 5075);
DISPLAY INVISIBLE (-5275 5075);
FORCEPROP 1 LAST PATH I4
J 0
(-5325 5225);
DISPLAY 0.978723 (-5325 5225);
PAINT WHITE (-5325 5225);
DISPLAY INVISIBLE (-5325 5225);
FORCEPROP 1 LAST PART_NUMBER CS03321FE09
J 0
(-5325 5200);
DISPLAY 0.808511 (-5325 5200);
DISPLAY INVISIBLE (-5325 5200);
FORCEADD M24M02DRMN6TP..1
(-3850 5100);
FORCEPROP 1 LAST LOCATION U19
J 0
(-4044 5440);
DISPLAY 0.723404 (-4044 5440);
PAINT GREEN (-4044 5440);
FORCEPROP 0 LAST $SEC 1
J 0
(-4025 5575);
DISPLAY 0.680851 (-4025 5575);
PAINT MONO (-4025 5575);
DISPLAY INVISIBLE (-4025 5575);
FORCEPROP 0 LAST CDS_SEC 1
J 0
(-4025 5575);
DISPLAY 0.680851 (-4025 5575);
DISPLAY INVISIBLE (-4025 5575);
FORCEPROP 0 LASTPIN (-3525 5175) $PN 1
J 0
(-3515 5185);
DISPLAY 0.680851 (-3515 5185);
PAINT MONO (-3515 5185);
FORCEPROP 0 LASTPIN (-3525 5125) $PN 2
J 0
(-3515 5135);
DISPLAY 0.680851 (-3515 5135);
PAINT MONO (-3515 5135);
FORCEPROP 0 LASTPIN (-3525 5075) $PN 3
J 0
(-3515 5085);
DISPLAY 0.680851 (-3515 5085);
PAINT MONO (-3515 5085);
FORCEPROP 0 LASTPIN (-4175 5075) $PN 6
J 2
(-4185 5085);
DISPLAY 0.680851 (-4185 5085);
PAINT MONO (-4185 5085);
FORCEPROP 0 LASTPIN (-4175 5025) $PN 5
J 2
(-4185 5035);
DISPLAY 0.680851 (-4185 5035);
PAINT MONO (-4185 5035);
FORCEPROP 0 LASTPIN (-4175 5175) $PN 8
J 2
(-4185 5185);
DISPLAY 0.680851 (-4185 5185);
PAINT MONO (-4185 5185);
FORCEPROP 0 LASTPIN (-3525 5025) $PN 4
J 0
(-3515 5035);
DISPLAY 0.680851 (-3515 5035);
PAINT MONO (-3515 5035);
FORCEPROP 0 LASTPIN (-4175 5125) $PN 7
J 2
(-4185 5135);
DISPLAY 0.680851 (-4185 5135);
PAINT MONO (-4185 5135);
FORCEPROP 2 LAST PART_TYPE SMLF
J 0
(-4025 5525);
DISPLAY 0.680851 (-4025 5525);
FORCEPROP 1 LAST MATERIAL IC
J 0
(-4044 5232);
DISPLAY 0.723404 (-4044 5232);
PAINT GREEN (-4044 5232);
FORCEPROP 2 LAST VALUE M24M02-DRMN6TP
J 0
(-4025 5475);
DISPLAY 0.680851 (-4025 5475);
FORCEPROP 2 LAST CDS_LIB pure_quanta
J 0
(-3850 5100);
DISPLAY INVISIBLE (-3850 5100);
FORCEPROP 1 LAST CDS_LMAN_SYM_OUTLINE -175,125,175,-125
J 0
(-3850 5100);
DISPLAY 0.468085 (-3850 5100);
PAINT GREEN (-3850 5100);
DISPLAY INVISIBLE (-3850 5100);
FORCEPROP 1 LAST NEEDS_NO_SIZE TRUE
J 0
(-3675 5032);
DISPLAY 0.723404 (-3675 5032);
PAINT GREEN (-3675 5032);
DISPLAY INVISIBLE (-3675 5032);
FORCEPROP 1 LAST PATH I5
J 0
(-3675 4975);
DISPLAY 0.723404 (-3675 4975);
PAINT GREEN (-3675 4975);
DISPLAY INVISIBLE (-3675 4975);
FORCEPROP 1 LAST PART_NUMBER AKE33Z00600
J 0
(-4044 5326);
DISPLAY 0.723404 (-4044 5326);
PAINT GREEN (-4044 5326);
DISPLAY INVISIBLE (-4044 5326);
FORCEADD QUANTA_TITLE_BLOCK_C..1
(0 0);
FORCEPROP 0 LAST CDS_CON_LAST_MODIFIED Thu Sep 14 16:13:00 2023
J 0
(-1885 15);
DISPLAY INVISIBLE (-1885 15);
FORCEPROP 1 LAST CUSTOM_TXT_CDS <CON_LAST_MODIFIED>
J 0
(-1885 15);
DISPLAY 0.978723 (-1885 15);
FORCEPROP 2 LAST CUSTOM_TXT_CDS <XR_PAGE_TITLE>
J 0
(-7890 5250);
DISPLAY 0.638298 (-7890 5250);
PAINT PINK (-7890 5250);
DISPLAY INVISIBLE (-7890 5250);
FORCEPROP 1 LAST CUSTOM_TXT_CDS <NAME_2>
J 0
(-3175 50);
FORCEPROP 1 LAST CUSTOM_TXT_CDS <NAME_1>
J 0
(-3175 175);
FORCEPROP 1 LAST CUSTOM_TXT_CDS <Q_NUMBER>
J 0
(-1403 103);
DISPLAY 1.212766 (-1403 103);
FORCEPROP 1 LAST CUSTOM_TXT_CDS <Q_PROJ>
J 0
(-2382 102);
DISPLAY 1.212766 (-2382 102);
FORCEPROP 1 LAST CUSTOM_TXT_CDS <Q_REV>
J 0
(-184 103);
DISPLAY 1.212766 (-184 103);
FORCEPROP 1 LAST CUSTOM_TXT_CDS <CON_PAGE_NUM> OF <CON_TOTAL_PAGES>
J 0
(-446 18);
DISPLAY 0.978723 (-446 18);
FORCEPROP 1 LAST Q_TITLE RETIMER_CPU1_P1(7)
J 0
(-9366 26);
DISPLAY 2.446809 (-9366 26);
PAINT GREEN (-9366 26);
FORCEPROP 2 LAST PAGE_BORDER TRUE
J 0
(-7890 5250);
DISPLAY 0.638298 (-7890 5250);
PAINT PINK (-7890 5250);
DISPLAY INVISIBLE (-7890 5250);
FORCEPROP 1 LAST CDS_LMAN_SYM_OUTLINE -9475,6775,100,-125
J 0
(0 0);
DISPLAY 0.468085 (0 0);
PAINT GREEN (0 0);
DISPLAY INVISIBLE (0 0);
FORCEPROP 2 LAST CDS_LIB pure_quanta
J 0
(0 0);
DISPLAY INVISIBLE (0 0);
FORCEPROP 2 LAST CDS_XR_PAGE_TITLE CR-334 : @T6G_MB_LIB.T6G(SCH_1):PAGE334
J 0
(-7890 5250);
DISPLAY 0.638298 (-7890 5250);
PAINT PINK (-7890 5250);
DISPLAY INVISIBLE (-7890 5250);
FORCEPROP 1 LAST Q_DEPT BU9
J 1
(-3763 49);
DISPLAY 1.957447 (-3763 49);
PAINT GREEN (-3763 49);
DISPLAY INVISIBLE (-3763 49);
FORCEPROP 1 LAST COMMENT_BODY TRUE
J 0
(12 -13);
DISPLAY 0.978723 (12 -13);
PAINT GREEN (12 -13);
DISPLAY INVISIBLE (12 -13);
WIRE 16 -1 (-3525 5025)(-3025 5025);
WIRE 16 -1 (-3025 5025)(-3025 4900);
WIRE 16 -1 (-2875 4800)(-2875 4675);
WIRE 16 -1 (-4600 5525)(-4600 5375);
WIRE 16 -1 (-4175 5125)(-4275 5125);
WIRE 16 -1 (-6825 5025)(-5375 5025);
FORCEPROP 2 LAST SIG_NAME SMB_RT_CPU1_P1_ROM_R_SDA
J 0
(-6735 5035);
DISPLAY 0.680851 (-6735 5035);
WIRE 16 -1 (-4175 5025)(-5175 5025);
FORCEPROP 2 LAST SIG_NAME SMB_RT_CPU1_P1_ROM_SDA
J 0
(-5060 5035);
DISPLAY 0.680851 (-5060 5035);
FORCEPROP 2 LASTPROP $XRERR UNIQUE?
J 0
(-5300 5035);
DISPLAY 0.638298 (-5300 5035);
PAINT MONO (-5300 5035);
DISPLAY INVISIBLE (-5300 5035);
WIRE 16 -1 (-6825 5075)(-5375 5075);
FORCEPROP 2 LAST SIG_NAME SMB_RT_CPU1_P1_ROM_R_SCL
J 0
(-6710 5085);
DISPLAY 0.680851 (-6710 5085);
WIRE 16 -1 (-4175 5075)(-5175 5075);
FORCEPROP 2 LAST SIG_NAME SMB_RT_CPU1_P1_ROM_SCL
J 0
(-5060 5085);
DISPLAY 0.680851 (-5060 5085);
FORCEPROP 2 LASTPROP $XRERR UNIQUE?
J 0
(-5300 5085);
DISPLAY 0.638298 (-5300 5085);
PAINT MONO (-5300 5085);
DISPLAY INVISIBLE (-5300 5085);
WIRE 16 -1 (-3525 5075)(-2875 5075);
FORCEPROP 2 LAST SIG_NAME U19_E2
J 0
(-3360 5085);
DISPLAY 0.680851 (-3360 5085);
FORCEPROP 2 LASTPROP $XRERR UNIQUE?
J 0
(-3600 5085);
DISPLAY 0.638298 (-3600 5085);
PAINT MONO (-3600 5085);
DISPLAY INVISIBLE (-3600 5085);
WIRE 16 -1 (-2875 5075)(-2875 5000);
WIRE 16 -1 (-4325 5825)(-4325 5800);
WIRE 16 -1 (-4600 5800)(-4325 5800);
WIRE 16 -1 (-4325 5800)(-4325 5175);
WIRE 16 -1 (-4325 5175)(-4175 5175);
WIRE 16 -1 (-4600 5725)(-4600 5800);
DOT 1 (-4325 5800);
FORCENOTE
RETIMER EEPRO ADDRESS: 0XA0 (8 BIT) / 0X50 (7 BIT)
(-6800 4575) 0;
DISPLAY LEFT (-6800 4575);
DISPLAY 1.595745 (-6800 4575);
QUIT
